# S9S_MB_2U (Grand Teton) — schematic netlist excerpt (pin names and nets, part order shuffled) for the footprints in the layout excerpt that follows; sources: Cadence DE-HDL packaged netlist, KiCad conversion of 03242023_DA0F0TMBIJ0_F0T_Motherboard_J_brd_V01_OCP.brd

PR301  Q_RES  0 5% CHIP  pkg 0402LF  page 286 : A = PVCCIN_CPU1_VOS4 ; B = PVCCIN_CPU1
R1002  Q_RES  4.7K 5% CHIP  pkg 0402LF  page 235 : A = P3V3 ; B = FM_SMB_CPU0_ALERT_R1

(kicad_pcb
	(version 20260206)
	(generator "pcbnew")
	(generator_version "10.0")
	(general
		(thickness 1.6)
		(legacy_teardrops no)
	)
	(paper "A4")
	(title_block
		(title "03242023_DA0F0TMBIJ0_F0T_Motherboard_J_brd_V01_OCP.brd")
		(comment 1 "Grand Teton / footprints 5612-5613 of 6105")
	)
	(layers
		(0 "F.Cu" signal "TOP")
		(4 "In1.Cu" signal "GND")
		(6 "In2.Cu" signal "IN1")
		(8 "In3.Cu" signal "GND1")
		(10 "In4.Cu" signal "IN2")
		(12 "In5.Cu" signal "GND2")
		(14 "In6.Cu" signal "IN3")
		(16 "In7.Cu" signal "GND3")
		(18 "In8.Cu" signal "VCC")
		(20 "In9.Cu" signal "VCC1")
		(22 "In10.Cu" signal "GND4")
		(24 "In11.Cu" signal "IN4")
		(26 "In12.Cu" signal "GND5")
		(28 "In13.Cu" signal "IN5")
		(30 "In14.Cu" signal "GND6")
		(32 "In15.Cu" signal "IN6")
		(34 "In16.Cu" signal "GND7")
		(2 "B.Cu" signal "BOTTOM")
		(9 "F.Adhes" user "F.Adhesive")
		(11 "B.Adhes" user "B.Adhesive")
		(13 "F.Paste" user "Package Geometry/Pastemask Top")
		(15 "B.Paste" user "Package Geometry/Pastemask Bottom")
		(5 "F.SilkS" user "Ref Des/Silkscreen Top")
		(7 "B.SilkS" user "Ref Des/Silkscreen Bottom")
		(1 "F.Mask" user "Board Geometry/Soldermask Top")
		(3 "B.Mask" user "Board Geometry/Soldermask Bottom")
		(17 "Dwgs.User" user "User.Drawings")
		(19 "Cmts.User" user "User.Comments")
		(21 "Eco1.User" user "User.Eco1")
		(23 "Eco2.User" user "User.Eco2")
		(25 "Edge.Cuts" user "Board Geometry/Outline")
		(27 "Margin" user)
		(31 "F.CrtYd" user "Package Geometry/Place Bound Top")
		(29 "B.CrtYd" user "Package Geometry/Place Bound Bottom")
		(35 "F.Fab" user "Ref Des/Assembly Top")
		(33 "B.Fab" user "Ref Des/Assembly Bottom")
	)
	(footprint ""
		(layer "B.Cu")
		(at 365.429038 -180.99405)
		(property "Reference" "R1002"
			(at 0 0 0)
			(layer "B.SilkS")
			(hide yes)
			(effects
				(font
					(size 1.27 1.27)
				)
				(justify mirror)
			)
		)
		(property "Value" ""
			(at 0 0 0)
			(layer "B.Fab")
			(effects
				(font
					(size 1.27 1.27)
				)
				(justify mirror)
			)
		)
		(duplicate_pad_numbers_are_jumpers no)
		(fp_line
			(start -0.7874 -0.4064)
			(end -0.7874 0.4064)
			(stroke
				(width 0.1524)
				(type default)
			)
			(layer "B.SilkS")
		)
		(fp_line
			(start -0.7874 0.4064)
			(end 0.7874 0.4064)
			(stroke
				(width 0.1524)
				(type default)
			)
			(layer "B.SilkS")
		)
		(fp_line
			(start 0.7874 -0.4064)
			(end -0.7874 -0.4064)
			(stroke
				(width 0.1524)
				(type default)
			)
			(layer "B.SilkS")
		)
		(fp_line
			(start 0.7874 0.4064)
			(end 0.7874 -0.4064)
			(stroke
				(width 0.1524)
				(type default)
			)
			(layer "B.SilkS")
		)
		(fp_line
			(start -0.67945 -0.3048)
			(end -0.67945 0.3048)
			(stroke
				(width 0.1)
				(type default)
			)
			(layer "B.Fab")
		)
		(fp_line
			(start -0.67945 0.3048)
			(end -0.120396 0.3048)
			(stroke
				(width 0.1)
				(type default)
			)
			(layer "B.Fab")
		)
		(fp_line
			(start -0.12065 -0.3048)
			(end -0.67945 -0.3048)
			(stroke
				(width 0.1)
				(type default)
			)
			(layer "B.Fab")
		)
		(fp_line
			(start -0.12065 -0.2794)
			(end -0.12065 -0.3048)
			(stroke
				(width 0.1)
				(type default)
			)
			(layer "B.Fab")
		)
		(fp_line
			(start -0.120396 0.2794)
			(end 0.12065 0.2794)
			(stroke
				(width 0.1)
				(type default)
			)
			(layer "B.Fab")
		)
		(fp_line
			(start -0.120396 0.3048)
			(end -0.120396 0.2794)
			(stroke
				(width 0.1)
				(type default)
			)
			(layer "B.Fab")
		)
		(fp_line
			(start 0.12065 -0.305054)
			(end 0.12065 -0.2794)
			(stroke
				(width 0.1)
				(type default)
			)
			(layer "B.Fab")
		)
		(fp_line
			(start 0.12065 -0.2794)
			(end -0.12065 -0.2794)
			(stroke
				(width 0.1)
				(type default)
			)
			(layer "B.Fab")
		)
		(fp_line
			(start 0.12065 0.2794)
			(end 0.12065 0.3048)
			(stroke
				(width 0.1)
				(type default)
			)
			(layer "B.Fab")
		)
		(fp_line
			(start 0.12065 0.3048)
			(end 0.67945 0.3048)
			(stroke
				(width 0.1)
				(type default)
			)
			(layer "B.Fab")
		)
		(fp_line
			(start 0.67945 -0.305054)
			(end 0.12065 -0.305054)
			(stroke
				(width 0.1)
				(type default)
			)
			(layer "B.Fab")
		)
		(fp_line
			(start 0.67945 0.3048)
			(end 0.67945 -0.305054)
			(stroke
				(width 0.1)
				(type default)
			)
			(layer "B.Fab")
		)
		(pad "1" smd circle
			(at 0.40005 0 180)
			(size 0 0)
			(layers "B.Cu" "B.Mask" "B.Paste")
			(net "P3V3")
		)
		(pad "2" smd circle
			(at -0.40005 0 180)
			(size 0 0)
			(layers "B.Cu" "B.Mask" "B.Paste")
			(net "FM_SMB_CPU0_ALERT_R1")
		)
	)
	(footprint ""
		(layer "B.Cu")
		(at 117.904514 -336.192368 -90)
		(property "Reference" "PR301"
			(at 0 0 90)
			(layer "B.SilkS")
			(hide yes)
			(effects
				(font
					(size 1.27 1.27)
				)
				(justify mirror)
			)
		)
		(property "Value" ""
			(at 0 0 90)
			(layer "B.Fab")
			(effects
				(font
					(size 1.27 1.27)
				)
				(justify mirror)
			)
		)
		(duplicate_pad_numbers_are_jumpers no)
		(fp_line
			(start -0.7874 0.4064)
			(end 0.7874 0.4064)
			(stroke
				(width 0.1524)
				(type default)
			)
			(layer "B.SilkS")
		)
		(fp_line
			(start 0.7874 0.4064)
			(end 0.7874 -0.4064)
			(stroke
				(width 0.1524)
				(type default)
			)
			(layer "B.SilkS")
		)
		(fp_line
			(start -0.7874 -0.4064)
			(end -0.7874 0.4064)
			(stroke
				(width 0.1524)
				(type default)
			)
			(layer "B.SilkS")
		)
		(fp_line
			(start 0.7874 -0.4064)
			(end -0.7874 -0.4064)
			(stroke
				(width 0.1524)
				(type default)
			)
			(layer "B.SilkS")
		)
		(fp_line
			(start -0.67945 0.3048)
			(end -0.120396 0.3048)
			(stroke
				(width 0.1)
				(type default)
			)
			(layer "B.Fab")
		)
		(fp_line
			(start -0.120396 0.3048)
			(end -0.120396 0.2794)
			(stroke
				(width 0.1)
				(type default)
			)
			(layer "B.Fab")
		)
		(fp_line
			(start 0.12065 0.3048)
			(end 0.67945 0.3048)
			(stroke
				(width 0.1)
				(type default)
			)
			(layer "B.Fab")
		)
		(fp_line
			(start 0.67945 0.3048)
			(end 0.67945 -0.305054)
			(stroke
				(width 0.1)
				(type default)
			)
			(layer "B.Fab")
		)
		(fp_line
			(start -0.120396 0.2794)
			(end 0.12065 0.2794)
			(stroke
				(width 0.1)
				(type default)
			)
			(layer "B.Fab")
		)
		(fp_line
			(start 0.12065 0.2794)
			(end 0.12065 0.3048)
			(stroke
				(width 0.1)
				(type default)
			)
			(layer "B.Fab")
		)
		(fp_line
			(start -0.12065 -0.2794)
			(end -0.12065 -0.3048)
			(stroke
				(width 0.1)
				(type default)
			)
			(layer "B.Fab")
		)
		(fp_line
			(start 0.12065 -0.2794)
			(end -0.12065 -0.2794)
			(stroke
				(width 0.1)
				(type default)
			)
			(layer "B.Fab")
		)
		(fp_line
			(start -0.67945 -0.3048)
			(end -0.67945 0.3048)
			(stroke
				(width 0.1)
				(type default)
			)
			(layer "B.Fab")
		)
		(fp_line
			(start -0.12065 -0.3048)
			(end -0.67945 -0.3048)
			(stroke
				(width 0.1)
				(type default)
			)
			(layer "B.Fab")
		)
		(fp_line
			(start 0.12065 -0.305054)
			(end 0.12065 -0.2794)
			(stroke
				(width 0.1)
				(type default)
			)
			(layer "B.Fab")
		)
		(fp_line
			(start 0.67945 -0.305054)
			(end 0.12065 -0.305054)
			(stroke
				(width 0.1)
				(type default)
			)
			(layer "B.Fab")
		)
		(pad "1" smd circle
			(at 0.40005 0 90)
			(size 0 0)
			(layers "B.Cu" "B.Mask" "B.Paste")
			(net "PVCCIN_CPU1_VOS4")
		)
		(pad "2" smd circle
			(at -0.40005 0 90)
			(size 0 0)
			(layers "B.Cu" "B.Mask" "B.Paste")
			(net "PVCCIN_CPU1")
		)
	)
)
